(kicad_pcb
	(version 20221018)
	(generator pcbnew)
	(general
    (thickness 1.7403)
  )
	(paper "A4")
	(title_block
    (title "Data Center RDIMM DDR4 Tester")
    (date "2024-09-30")
    (rev "1.2.4")
		(comment 9 "footprints 564-565 of 690")
	)
	(layers
    (0 "F.Cu" signal)
    (1 "In1.Cu" power)
    (2 "In2.Cu" signal)
    (3 "In3.Cu" power)
    (4 "In4.Cu" power)
    (5 "In5.Cu" signal)
    (6 "In6.Cu" power)
    (7 "In7.Cu" signal)
    (8 "In8.Cu" power)
    (9 "In9.Cu" signal)
    (10 "In10.Cu" power)
    (31 "B.Cu" signal)
    (32 "B.Adhes" user "B.Adhesive")
    (33 "F.Adhes" user "F.Adhesive")
    (34 "B.Paste" user)
    (35 "F.Paste" user)
    (36 "B.SilkS" user "B.Silkscreen")
    (37 "F.SilkS" user "F.Silkscreen")
    (38 "B.Mask" user)
    (39 "F.Mask" user)
    (40 "Dwgs.User" user "User.Drawings")
    (41 "Cmts.User" user "User.Comments")
    (42 "Eco1.User" user "User.Eco1")
    (43 "Eco2.User" user "User.Eco2")
    (44 "Edge.Cuts" user)
    (45 "Margin" user)
    (46 "B.CrtYd" user "B.Courtyard")
    (47 "F.CrtYd" user "F.Courtyard")
    (48 "B.Fab" user)
    (49 "F.Fab" user)
  )
	(footprint "data-center-rdimm-ddr4-tester-footprints:WQFN-56-1EP_5x11x1mm_P0.5mm" (layer "B.Cu")
    (at 159.1645 106.6705 -90)
    (property "Author" "Antmicro")
    (property "License" "Apache-2.0")
    (property "MPN" "TS3L500RHUR")
    (property "Manufacturer" "Texas Instruments")
    (property "Sheetfile" "ethernet.kicad_sch")
    (property "Sheetname" "Ethernet")
    (property "ki_description" "3.3-V, 2:1 (SPDT), 8-channel gigachannel LAN switch with LED switch & enhanced ESD protection")
    (attr smd)
    (fp_text reference "U16" (at -2.2805 5.9445 180) (layer "B.SilkS")
        (effects (font (size 0.7 0.7) (thickness 0.15)) (justify left bottom mirror))
    )
    (fp_text value "TS3L500RHUR" (at -0.02 -7.02 90) (layer "B.Fab") hide
        (effects (font (size 0.7 0.7) (thickness 0.15)) (justify left bottom mirror))
    )
    (fp_text user "Author: Antmicro" (at -0.482 -14.749 90) (layer "B.Fab") hide
        (effects (font (size 0.7 0.7) (thickness 0.15)) (justify left bottom mirror))
    )
    (fp_text user "${REFERENCE}" (at -0.482 -13.749 90) (layer "B.Fab") hide
        (effects (font (size 0.7 0.7) (thickness 0.15)) (justify left bottom mirror))
    )
    (fp_text user "License: Apache-2.0" (at -0.482 -15.749 90) (layer "B.Fab") hide
        (effects (font (size 0.7 0.7) (thickness 0.15)) (justify left bottom mirror))
    )
    (fp_line (start -2.956 5.218) (end -3.356 5.218)
      (stroke (width 0.15) (type solid)) (layer "B.SilkS"))
    (fp_line (start -2.956 5.955) (end -2.956 5.218)
      (stroke (width 0.15) (type solid)) (layer "B.SilkS"))
    (fp_line (start -2.218 5.955) (end -2.956 5.955)
      (stroke (width 0.15) (type solid)) (layer "B.SilkS"))
    (fp_line (start 2.955 5.218) (end 2.955 5.955)
      (stroke (width 0.15) (type solid)) (layer "B.SilkS"))
    (fp_line (start 2.955 5.955) (end 2.219 5.955)
      (stroke (width 0.15) (type solid)) (layer "B.SilkS"))
    (fp_circle (center -3.5 4.749) (end -3.45 4.699)
      (stroke (width 0.15) (type solid)) (fill solid) (layer "B.SilkS"))
    (fp_rect (start -3.15 6.15) (end 3.15 -6.15)
      (stroke (width 0.05) (type solid)) (fill none) (layer "B.CrtYd"))
    (fp_line (start -2.576 -5.576) (end 2.575 -5.576)
      (stroke (width 0.15) (type solid)) (layer "B.Fab"))
    (fp_line (start -2.576 4.305) (end -2.576 -5.576)
      (stroke (width 0.15) (type solid)) (layer "B.Fab"))
    (fp_line (start -2.576 4.305) (end -1.305 5.575)
      (stroke (width 0.15) (type solid)) (layer "B.Fab"))
    (fp_line (start 2.575 -5.576) (end 2.575 5.575)
      (stroke (width 0.15) (type solid)) (layer "B.Fab"))
    (fp_line (start 2.575 5.575) (end -1.305 5.575)
      (stroke (width 0.15) (type solid)) (layer "B.Fab"))
    (pad "1" smd roundrect (at -2.474 4.749 180) (size 0.28 0.85) (layers "B.Cu" "B.Paste" "B.Mask") (roundrect_rratio 0.25)
      (net 9 "GND") (pinfunction "GND") (pintype "power_in"))
    (pad "2" smd roundrect (at -2.474 4.25 180) (size 0.28 0.85) (layers "B.Cu" "B.Paste" "B.Mask") (roundrect_rratio 0.25)
      (net 170 "/Ethernet/ETH1_P") (pinfunction "A0") (pintype "bidirectional"))
    (pad "3" smd roundrect (at -2.474 3.75 180) (size 0.28 0.85) (layers "B.Cu" "B.Paste" "B.Mask") (roundrect_rratio 0.25)
      (net 173 "/Ethernet/ETH1_N") (pinfunction "A1") (pintype "bidirectional"))
    (pad "4" smd roundrect (at -2.474 3.25 180) (size 0.28 0.85) (layers "B.Cu" "B.Paste" "B.Mask") (roundrect_rratio 0.25)
      (net 143 "3V3_SYS") (pinfunction "VCC") (pintype "passive"))
    (pad "5" smd roundrect (at -2.474 2.75 180) (size 0.28 0.85) (layers "B.Cu" "B.Paste" "B.Mask") (roundrect_rratio 0.25)
      (net 914 "unconnected-(U16-NC-Pad5)") (pinfunction "NC") (pintype "no_connect"))
    (pad "6" smd roundrect (at -2.474 2.25 180) (size 0.28 0.85) (layers "B.Cu" "B.Paste" "B.Mask") (roundrect_rratio 0.25)
      (net 9 "GND") (pinfunction "GND") (pintype "passive"))
    (pad "7" smd roundrect (at -2.474 1.75 180) (size 0.28 0.85) (layers "B.Cu" "B.Paste" "B.Mask") (roundrect_rratio 0.25)
      (net 169 "/Ethernet/ETH2_P") (pinfunction "A2") (pintype "bidirectional"))
    (pad "8" smd roundrect (at -2.474 1.25 180) (size 0.28 0.85) (layers "B.Cu" "B.Paste" "B.Mask") (roundrect_rratio 0.25)
      (net 172 "/Ethernet/ETH2_N") (pinfunction "A3") (pintype "bidirectional"))
    (pad "9" smd roundrect (at -2.474 0.75 180) (size 0.28 0.85) (layers "B.Cu" "B.Paste" "B.Mask") (roundrect_rratio 0.25)
      (net 9 "GND") (pinfunction "GND") (pintype "passive"))
    (pad "10" smd roundrect (at -2.474 0.25 180) (size 0.28 0.85) (layers "B.Cu" "B.Paste" "B.Mask") (roundrect_rratio 0.25)
      (net 143 "3V3_SYS") (pinfunction "VCC") (pintype "power_in"))
    (pad "11" smd roundrect (at -2.474 -0.25 180) (size 0.28 0.85) (layers "B.Cu" "B.Paste" "B.Mask") (roundrect_rratio 0.25)
      (net 168 "/Ethernet/ETH3_P") (pinfunction "A4") (pintype "bidirectional"))
    (pad "12" smd roundrect (at -2.474 -0.75 180) (size 0.28 0.85) (layers "B.Cu" "B.Paste" "B.Mask") (roundrect_rratio 0.25)
      (net 174 "/Ethernet/ETH3_N") (pinfunction "A5") (pintype "bidirectional"))
    (pad "13" smd roundrect (at -2.474 -1.25 180) (size 0.28 0.85) (layers "B.Cu" "B.Paste" "B.Mask") (roundrect_rratio 0.25)
      (net 9 "GND") (pinfunction "GND") (pintype "passive"))
    (pad "14" smd roundrect (at -2.474 -1.75 180) (size 0.28 0.85) (layers "B.Cu" "B.Paste" "B.Mask") (roundrect_rratio 0.25)
      (net 171 "/Ethernet/ETH4_P") (pinfunction "A6") (pintype "bidirectional"))
    (pad "15" smd roundrect (at -2.474 -2.25 180) (size 0.28 0.85) (layers "B.Cu" "B.Paste" "B.Mask") (roundrect_rratio 0.25)
      (net 175 "/Ethernet/ETH4_N") (pinfunction "A7") (pintype "bidirectional"))
    (pad "16" smd roundrect (at -2.474 -2.75 180) (size 0.28 0.85) (layers "B.Cu" "B.Paste" "B.Mask") (roundrect_rratio 0.25)
      (net 9 "GND") (pinfunction "GND") (pintype "passive"))
    (pad "17" smd roundrect (at -2.474 -3.25 180) (size 0.28 0.85) (layers "B.Cu" "B.Paste" "B.Mask") (roundrect_rratio 0.25)
      (net 662 "Net-(U16-SEL)") (pinfunction "SEL") (pintype "input"))
    (pad "18" smd roundrect (at -2.474 -3.75 180) (size 0.28 0.85) (layers "B.Cu" "B.Paste" "B.Mask") (roundrect_rratio 0.25)
      (net 143 "3V3_SYS") (pinfunction "VCC") (pintype "passive"))
    (pad "19" smd roundrect (at -2.474 -4.25 180) (size 0.28 0.85) (layers "B.Cu" "B.Paste" "B.Mask") (roundrect_rratio 0.25)
      (net 9 "GND") (pinfunction "LED0") (pintype "bidirectional"))
    (pad "20" smd roundrect (at -2.474 -4.75 180) (size 0.28 0.85) (layers "B.Cu" "B.Paste" "B.Mask") (roundrect_rratio 0.25)
      (net 16 "LED_LINK") (pinfunction "LED1") (pintype "bidirectional"))
    (pad "21" smd roundrect (at -1.751 -5.475 270) (size 0.28 0.85) (layers "B.Cu" "B.Paste" "B.Mask") (roundrect_rratio 0.25)
      (net 9 "GND") (pinfunction "GND") (pintype "passive"))
    (pad "22" smd roundrect (at -1.251 -5.475 270) (size 0.28 0.85) (layers "B.Cu" "B.Paste" "B.Mask") (roundrect_rratio 0.25)
      (net 915 "unconnected-(U16-0LED1-Pad22)") (pinfunction "0LED1") (pintype "bidirectional+no_connect"))
    (pad "23" smd roundrect (at -0.751 -5.475 270) (size 0.28 0.85) (layers "B.Cu" "B.Paste" "B.Mask") (roundrect_rratio 0.25)
      (net 736 "EXT_LED_LINK") (pinfunction "1LED1") (pintype "bidirectional"))
    (pad "24" smd roundrect (at -0.25 -5.475 270) (size 0.28 0.85) (layers "B.Cu" "B.Paste" "B.Mask") (roundrect_rratio 0.25)
      (net 9 "GND") (pinfunction "GND") (pintype "passive"))
    (pad "25" smd roundrect (at 0.251 -5.475 270) (size 0.28 0.85) (layers "B.Cu" "B.Paste" "B.Mask") (roundrect_rratio 0.25)
      (net 916 "unconnected-(U16-0LED2-Pad25)") (pinfunction "0LED2") (pintype "bidirectional+no_connect"))
    (pad "26" smd roundrect (at 0.751 -5.475 270) (size 0.28 0.85) (layers "B.Cu" "B.Paste" "B.Mask") (roundrect_rratio 0.25)
      (net 537 "INT_LED_LINK") (pinfunction "1LED2") (pintype "bidirectional"))
    (pad "27" smd roundrect (at 1.251 -5.475 270) (size 0.28 0.85) (layers "B.Cu" "B.Paste" "B.Mask") (roundrect_rratio 0.25)
      (net 143 "3V3_SYS") (pinfunction "VCC") (pintype "passive"))
    (pad "28" smd roundrect (at 1.75 -5.475 270) (size 0.28 0.85) (layers "B.Cu" "B.Paste" "B.Mask") (roundrect_rratio 0.25)
      (net 9 "GND") (pinfunction "GND") (pintype "passive"))
    (pad "29" smd roundrect (at 2.474 -4.75 180) (size 0.28 0.85) (layers "B.Cu" "B.Paste" "B.Mask") (roundrect_rratio 0.25)
      (net 547 "/Ethernet/INT_ETH4_N") (pinfunction "7B2") (pintype "bidirectional"))
    (pad "30" smd roundrect (at 2.474 -4.25 180) (size 0.28 0.85) (layers "B.Cu" "B.Paste" "B.Mask") (roundrect_rratio 0.25)
      (net 548 "/Ethernet/INT_ETH4_P") (pinfunction "6B2") (pintype "bidirectional"))
    (pad "31" smd roundrect (at 2.474 -3.75 180) (size 0.28 0.85) (layers "B.Cu" "B.Paste" "B.Mask") (roundrect_rratio 0.25)
      (net 741 "EXT_ETH4_N") (pinfunction "7B1") (pintype "bidirectional"))
    (pad "32" smd roundrect (at 2.474 -3.25 180) (size 0.28 0.85) (layers "B.Cu" "B.Paste" "B.Mask") (roundrect_rratio 0.25)
      (net 740 "EXT_ETH4_P") (pinfunction "6B1") (pintype "bidirectional"))
    (pad "33" smd roundrect (at 2.474 -2.75 180) (size 0.28 0.85) (layers "B.Cu" "B.Paste" "B.Mask") (roundrect_rratio 0.25)
      (net 9 "GND") (pinfunction "GND") (pintype "passive"))
    (pad "34" smd roundrect (at 2.474 -2.25 180) (size 0.28 0.85) (layers "B.Cu" "B.Paste" "B.Mask") (roundrect_rratio 0.25)
      (net 558 "/Ethernet/INT_ETH3_N") (pinfunction "5B2") (pintype "bidirectional"))
    (pad "35" smd roundrect (at 2.474 -1.75 180) (size 0.28 0.85) (layers "B.Cu" "B.Paste" "B.Mask") (roundrect_rratio 0.25)
      (net 559 "/Ethernet/INT_ETH3_P") (pinfunction "4B2") (pintype "bidirectional"))
    (pad "36" smd roundrect (at 2.474 -1.25 180) (size 0.28 0.85) (layers "B.Cu" "B.Paste" "B.Mask") (roundrect_rratio 0.25)
      (net 757 "EXT_ETH3_N") (pinfunction "5B1") (pintype "bidirectional"))
    (pad "37" smd roundrect (at 2.474 -0.75 180) (size 0.28 0.85) (layers "B.Cu" "B.Paste" "B.Mask") (roundrect_rratio 0.25)
      (net 756 "EXT_ETH3_P") (pinfunction "4B1") (pintype "bidirectional"))
    (pad "38" smd roundrect (at 2.474 -0.25 180) (size 0.28 0.85) (layers "B.Cu" "B.Paste" "B.Mask") (roundrect_rratio 0.25)
      (net 143 "3V3_SYS") (pinfunction "VCC") (pintype "passive"))
    (pad "39" smd roundrect (at 2.474 0.25 180) (size 0.28 0.85) (layers "B.Cu" "B.Paste" "B.Mask") (roundrect_rratio 0.25)
      (net 9 "GND") (pinfunction "GND") (pintype "passive"))
    (pad "40" smd roundrect (at 2.474 0.75 180) (size 0.28 0.85) (layers "B.Cu" "B.Paste" "B.Mask") (roundrect_rratio 0.25)
      (net 567 "/Ethernet/INT_ETH2_N") (pinfunction "3B2") (pintype "bidirectional"))
    (pad "41" smd roundrect (at 2.474 1.25 180) (size 0.28 0.85) (layers "B.Cu" "B.Paste" "B.Mask") (roundrect_rratio 0.25)
      (net 568 "/Ethernet/INT_ETH2_P") (pinfunction "2B2") (pintype "bidirectional"))
    (pad "42" smd roundrect (at 2.474 1.75 180) (size 0.28 0.85) (layers "B.Cu" "B.Paste" "B.Mask") (roundrect_rratio 0.25)
      (net 739 "EXT_ETH2_N") (pinfunction "3B1") (pintype "bidirectional"))
    (pad "43" smd roundrect (at 2.474 2.25 180) (size 0.28 0.85) (layers "B.Cu" "B.Paste" "B.Mask") (roundrect_rratio 0.25)
      (net 738 "EXT_ETH2_P") (pinfunction "2B1") (pintype "bidirectional"))
    (pad "44" smd roundrect (at 2.474 2.75 180) (size 0.28 0.85) (layers "B.Cu" "B.Paste" "B.Mask") (roundrect_rratio 0.25)
      (net 9 "GND") (pinfunction "GND") (pintype "passive"))
    (pad "45" smd roundrect (at 2.474 3.25 180) (size 0.28 0.85) (layers "B.Cu" "B.Paste" "B.Mask") (roundrect_rratio 0.25)
      (net 630 "/Ethernet/INT_ETH1_N") (pinfunction "1B2") (pintype "bidirectional"))
    (pad "46" smd roundrect (at 2.474 3.75 180) (size 0.28 0.85) (layers "B.Cu" "B.Paste" "B.Mask") (roundrect_rratio 0.25)
      (net 631 "/Ethernet/INT_ETH1_P") (pinfunction "0B2") (pintype "bidirectional"))
    (pad "47" smd roundrect (at 2.474 4.25 180) (size 0.28 0.85) (layers "B.Cu" "B.Paste" "B.Mask") (roundrect_rratio 0.25)
      (net 755 "EXT_ETH1_N") (pinfunction "1B1") (pintype "bidirectional"))
    (pad "48" smd roundrect (at 2.474 4.749 180) (size 0.28 0.85) (layers "B.Cu" "B.Paste" "B.Mask") (roundrect_rratio 0.25)
      (net 754 "EXT_ETH1_P") (pinfunction "0B1") (pintype "bidirectional"))
    (pad "49" smd roundrect (at 1.75 5.474 270) (size 0.28 0.85) (layers "B.Cu" "B.Paste" "B.Mask") (roundrect_rratio 0.25)
      (net 9 "GND") (pinfunction "GND") (pintype "passive"))
    (pad "50" smd roundrect (at 1.251 5.474 270) (size 0.28 0.85) (layers "B.Cu" "B.Paste" "B.Mask") (roundrect_rratio 0.25)
      (net 143 "3V3_SYS") (pinfunction "VCC") (pintype "passive"))
    (pad "51" smd roundrect (at 0.751 5.474 270) (size 0.28 0.85) (layers "B.Cu" "B.Paste" "B.Mask") (roundrect_rratio 0.25)
      (net 546 "INT_LED_SPD") (pinfunction "2LED2") (pintype "bidirectional"))
    (pad "52" smd roundrect (at 0.251 5.474 270) (size 0.28 0.85) (layers "B.Cu" "B.Paste" "B.Mask") (roundrect_rratio 0.25)
      (net 737 "EXT_LED_SPD") (pinfunction "2LED1") (pintype "bidirectional"))
    (pad "53" smd roundrect (at -0.25 5.474 270) (size 0.28 0.85) (layers "B.Cu" "B.Paste" "B.Mask") (roundrect_rratio 0.25)
      (net 9 "GND") (pinfunction "GND") (pintype "passive"))
    (pad "54" smd roundrect (at -0.751 5.474 270) (size 0.28 0.85) (layers "B.Cu" "B.Paste" "B.Mask") (roundrect_rratio 0.25)
      (net 17 "LED_SPD") (pinfunction "LED2") (pintype "bidirectional"))
    (pad "55" smd roundrect (at -1.251 5.474 270) (size 0.28 0.85) (layers "B.Cu" "B.Paste" "B.Mask") (roundrect_rratio 0.25)
      (net 9 "GND") (pinfunction "GND") (pintype "passive"))
    (pad "56" smd roundrect (at -1.751 5.474 270) (size 0.28 0.85) (layers "B.Cu" "B.Paste" "B.Mask") (roundrect_rratio 0.25)
      (net 143 "3V3_SYS") (pinfunction "VCC") (pintype "passive"))
    (pad "57" smd roundrect (at -0.65 -3.2 270) (size 1 1) (layers "B.Cu" "B.Paste" "B.Mask") (roundrect_rratio 0.05)
      (net 9 "GND") (pinfunction "EP") (pintype "unspecified"))
    (pad "57" smd roundrect (at -0.65 -1.95 270) (size 1 1) (layers "B.Cu" "B.Paste" "B.Mask") (roundrect_rratio 0.05)
      (net 9 "GND") (pinfunction "EP") (pintype "unspecified"))
    (pad "57" smd roundrect (at -0.65 -0.65 270) (size 1 1) (layers "B.Cu" "B.Paste" "B.Mask") (roundrect_rratio 0.05)
      (net 9 "GND") (pinfunction "EP") (pintype "unspecified"))
    (pad "57" smd roundrect (at -0.65 0.65 270) (size 1 1) (layers "B.Cu" "B.Paste" "B.Mask") (roundrect_rratio 0.05)
      (net 9 "GND") (pinfunction "EP") (pintype "unspecified"))
    (pad "57" smd roundrect (at -0.65 1.9 270) (size 1 1) (layers "B.Cu" "B.Paste" "B.Mask") (roundrect_rratio 0.05)
      (net 9 "GND") (pinfunction "EP") (pintype "unspecified"))
    (pad "57" smd roundrect (at -0.65 3.2 270) (size 1 1) (layers "B.Cu" "B.Paste" "B.Mask") (roundrect_rratio 0.05)
      (net 9 "GND") (pinfunction "EP") (pintype "unspecified"))
    (pad "57" smd roundrect (at 0 0 270) (size 2.4 8.400001) (layers "B.Cu" "B.Mask") (roundrect_rratio 0.05)
      (net 9 "GND") (pinfunction "EP") (pintype "unspecified"))
    (pad "57" smd roundrect (at 0.65 -3.2 270) (size 1 1) (layers "B.Cu" "B.Paste" "B.Mask") (roundrect_rratio 0.05)
      (net 9 "GND") (pinfunction "EP") (pintype "unspecified"))
    (pad "57" smd roundrect (at 0.65 -1.95 270) (size 1 1) (layers "B.Cu" "B.Paste" "B.Mask") (roundrect_rratio 0.05)
      (net 9 "GND") (pinfunction "EP") (pintype "unspecified"))
    (pad "57" smd roundrect (at 0.65 -0.65 270) (size 1 1) (layers "B.Cu" "B.Paste" "B.Mask") (roundrect_rratio 0.05)
      (net 9 "GND") (pinfunction "EP") (pintype "unspecified"))
    (pad "57" smd roundrect (at 0.65 0.65 270) (size 1 1) (layers "B.Cu" "B.Paste" "B.Mask") (roundrect_rratio 0.05)
      (net 9 "GND") (pinfunction "EP") (pintype "unspecified"))
    (pad "57" smd roundrect (at 0.65 1.9 270) (size 1 1) (layers "B.Cu" "B.Paste" "B.Mask") (roundrect_rratio 0.05)
      (net 9 "GND") (pinfunction "EP") (pintype "unspecified"))
    (pad "57" smd roundrect (at 0.65 3.2 270) (size 1 1) (layers "B.Cu" "B.Paste" "B.Mask") (roundrect_rratio 0.05)
      (net 9 "GND") (pinfunction "EP") (pintype "unspecified"))
  )
	(footprint "data-center-rdimm-ddr4-tester-footprints:C_0201" (layer "B.Cu")
    (at 186.6 100.64)
    (descr "Capacitor SMD 0201")
    (tags "capacitor SMD 0201")
    (property "Author" "Antmicro")
    (property "Dielectric" "")
    (property "License" "Apache-2.0")
    (property "MPN" "CC0201KRX6S5BB104")
    (property "Manufacturer" "Yaego")
    (property "Sheetfile" "fpga-power.kicad_sch")
    (property "Sheetname" "FPGA power")
    (property "Val" "100n")
    (property "Voltage" "")
    (property "ki_description" " ")
    (attr smd)
    (fp_text reference "C304" (at 1.48 -0.31 180) (layer "B.SilkS")
        (effects (font (size 0.7 0.7) (thickness 0.15)) (justify left bottom mirror))
    )
    (fp_text value "C_100n_0201" (at 0 -1.4 180) (layer "B.Fab") hide
        (effects (font (size 0.7 0.7) (thickness 0.15)) (justify left bottom mirror))
    )
    (fp_text user "${REFERENCE}" (at -0.72 -3.4 180) (layer "B.Fab") hide
        (effects (font (size 0.7 0.7) (thickness 0.15)) (justify left bottom mirror))
    )
    (fp_text user "License: Apache-2.0" (at -0.72 -4.4 180) (layer "B.Fab") hide
        (effects (font (size 0.7 0.7) (thickness 0.15)) (justify left bottom mirror))
    )
    (fp_text user "Author: Antmicro" (at -0.72 -5.4 180) (layer "B.Fab") hide
        (effects (font (size 0.7 0.7) (thickness 0.15)) (justify left bottom mirror))
    )
    (fp_rect (start -0.72 0.38) (end 0.72 -0.38)
      (stroke (width 0.05) (type solid)) (fill none) (layer "B.CrtYd"))
    (fp_rect (start 0.3 -0.15) (end -0.301 0.149)
      (stroke (width 0.15) (type solid)) (fill none) (layer "B.Fab"))
    (pad "" smd roundrect (at -0.349 0.002) (size 0.318 0.36) (layers "B.Paste") (roundrect_rratio 0.25))
    (pad "" smd roundrect (at 0.341 0.002) (size 0.318 0.36) (layers "B.Paste") (roundrect_rratio 0.25))
    (pad "1" smd roundrect (at -0.321 0.002) (size 0.46 0.4) (layers "B.Cu" "B.Mask") (roundrect_rratio 0.25)
      (net 143 "3V3_SYS") (pintype "passive"))
    (pad "2" smd roundrect (at 0.32 0.002) (size 0.46 0.4) (layers "B.Cu" "B.Mask") (roundrect_rratio 0.25)
      (net 9 "GND") (pintype "passive"))
  )
)
